(kicad_pcb
	(version 20260206)
	(generator "pcbnew")
	(generator_version "10.0")
	(general
		(thickness 1.6)
		(legacy_teardrops no)
	)
	(paper "A4")
	(title_block
		(title "Bryce Canyon_F.DPB_16315-1-OCP.brd")
		(comment 1 "Bryce Canyon / footprints 1308-1311 of 2223")
	)
	(layers
		(0 "F.Cu" signal "TOP")
		(4 "In1.Cu" signal "L2GND")
		(6 "In2.Cu" signal "L3")
		(8 "In3.Cu" signal "L4GND")
		(10 "In4.Cu" signal "L5")
		(12 "In5.Cu" signal "L6VCC")
		(14 "In6.Cu" signal "L7VCC")
		(16 "In7.Cu" signal "L8")
		(18 "In8.Cu" signal "L9GND")
		(20 "In9.Cu" signal "L10")
		(22 "In10.Cu" signal "L11GND")
		(2 "B.Cu" signal "BOTTOM")
		(9 "F.Adhes" user "F.Adhesive")
		(11 "B.Adhes" user "B.Adhesive")
		(13 "F.Paste" user "Package Geometry/Pastemask Top")
		(15 "B.Paste" user "Package Geometry/Pastemask Bottom")
		(5 "F.SilkS" user "Ref Des/Silkscreen Top")
		(7 "B.SilkS" user "Ref Des/Silkscreen Bottom")
		(1 "F.Mask" user "Board Geometry/Soldermask Top")
		(3 "B.Mask" user "Board Geometry/Soldermask Bottom")
		(17 "Dwgs.User" user "User.Drawings")
		(19 "Cmts.User" user "User.Comments")
		(21 "Eco1.User" user "User.Eco1")
		(23 "Eco2.User" user "User.Eco2")
		(25 "Edge.Cuts" user "Board Geometry/Outline")
		(27 "Margin" user)
		(31 "F.CrtYd" user "Package Geometry/Place Bound Top")
		(29 "B.CrtYd" user "Package Geometry/Place Bound Bottom")
		(35 "F.Fab" user "Ref Des/Assembly Top")
		(33 "B.Fab" user "Ref Des/Assembly Bottom")
	)
	(footprint ""
		(layer "F.Cu")
		(at 483.300024 -57.909968 -90)
		(property "Reference" "HDDSAS35"
			(at 0 0 270)
			(layer "F.SilkS")
			(hide yes)
			(effects
				(font
					(size 1.27 1.27)
				)
			)
		)
		(property "Value" "SKT-SAS15P-14P-45-GP"
			(at -20.7645 -8.9789 270)
			(unlocked yes)
			(layer "F.Fab")
			(hide yes)
			(effects
				(font
					(size 1.016 1.016)
					(thickness 0.1524)
				)
			)
		)
		(property "Device Type" "10120818-001C-TRLF"
			(at -20.7645 -10.5029 270)
			(unlocked yes)
			(layer "F.Fab")
			(hide yes)
			(effects
				(font
					(size 1.016 1.016)
					(thickness 0.1524)
				)
			)
		)
		(duplicate_pad_numbers_are_jumpers no)
		(fp_line
			(start 1.651 4.2926)
			(end 1.651 3.0099)
			(stroke
				(width 0.1524)
				(type default)
			)
			(layer "F.SilkS")
		)
		(fp_line
			(start 8.509 4.2926)
			(end 1.651 4.2926)
			(stroke
				(width 0.1524)
				(type default)
			)
			(layer "F.SilkS")
		)
		(fp_line
			(start -23.4188 3.0099)
			(end -23.4188 -3.2512)
			(stroke
				(width 0.1524)
				(type default)
			)
			(layer "F.SilkS")
		)
		(fp_line
			(start 1.651 3.0099)
			(end -23.4188 3.0099)
			(stroke
				(width 0.1524)
				(type default)
			)
			(layer "F.SilkS")
		)
		(fp_line
			(start 8.509 3.0099)
			(end 8.509 4.2926)
			(stroke
				(width 0.1524)
				(type default)
			)
			(layer "F.SilkS")
		)
		(fp_line
			(start 23.4188 3.0099)
			(end 8.509 3.0099)
			(stroke
				(width 0.1524)
				(type default)
			)
			(layer "F.SilkS")
		)
		(fp_line
			(start -23.4188 -3.2512)
			(end 23.4188 -3.2512)
			(stroke
				(width 0.1524)
				(type default)
			)
			(layer "F.SilkS")
		)
		(fp_line
			(start 23.4188 -3.2512)
			(end 23.4188 3.0099)
			(stroke
				(width 0.1524)
				(type default)
			)
			(layer "F.SilkS")
		)
		(fp_line
			(start 15.5067 -3.3401)
			(end 16.2687 -3.3401)
			(stroke
				(width 0.3302)
				(type default)
			)
			(layer "F.SilkS")
		)
		(fp_poly
			(pts
				(xy 15.868904 -3.230372) (xy 16.503904 -3.865372) (xy 15.233904 -3.865372)
			)
			(stroke
				(width 0)
				(type default)
			)
			(fill yes)
			(layer "F.SilkS")
		)
		(fp_poly
			(pts
				(xy -22.8727 -2.7559) (xy 22.8727 -2.7559) (xy 22.8727 2.7559) (xy 8.255 2.7559) (xy 8.255 3.5179)
				(xy 1.905 3.5179) (xy 1.905 2.7559) (xy -22.8727 2.7559)
			)
			(stroke
				(width 0)
				(type default)
			)
			(fill no)
			(layer "F.CrtYd")
		)
		(fp_poly
			(pts
				(xy 1.397 4.5466) (xy 1.397 3.2639) (xy -23.6728 3.2639) (xy -23.6728 -3.5052) (xy 23.6728 -3.5052)
				(xy 23.6728 -0.00635) (xy 22.8727 -0.00635) (xy 22.8727 -2.7559) (xy -22.8727 -2.7559) (xy -22.8727 2.7559)
				(xy 1.905 2.7559) (xy 1.905 3.5179) (xy 8.255 3.5179) (xy 8.255 2.7559) (xy 22.8727 2.7559) (xy 22.8727 0.00635)
				(xy 23.6728 0.00635) (xy 23.6728 3.2639) (xy 8.763 3.2639) (xy 8.763 4.5466)
			)
			(stroke
				(width 0)
				(type default)
			)
			(fill no)
			(layer "F.CrtYd")
		)
		(fp_poly
			(pts
				(xy 1.397 4.5466) (xy 1.397 3.2639) (xy -23.6728 3.2639) (xy -23.6728 -3.5052) (xy 23.6728 -3.5052)
				(xy 23.6728 3.2639) (xy 8.763 3.2639) (xy 8.763 4.5466)
			)
			(stroke
				(width 0)
				(type default)
			)
			(fill no)
			(layer "F.Fab")
		)
		(pad "" np_thru_hole circle
			(at -18.874994 0 270)
			(size 0.254 0.254)
			(drill 1.3462)
			(layers "*.Cu" "*.Mask")
			(clearance 0.9017)
			(thermal_gap 0.9017)
		)
		(pad "" np_thru_hole circle
			(at 18.874994 0 270)
			(size 0.254 0.254)
			(drill 0.9398)
			(layers "*.Cu" "*.Mask")
			(clearance 0.6985)
			(thermal_gap 0.6985)
		)
		(pad "G1" smd rect
			(at 21.874988 0 270)
			(size 2.5908 2.5908)
			(layers "F.Cu" "F.Mask" "F.Paste")
			(net "GND")
		)
		(pad "G2" smd rect
			(at -21.874988 0 270)
			(size 2.5908 2.5908)
			(layers "F.Cu" "F.Mask" "F.Paste")
			(net "GND")
		)
		(pad "P1" smd rect
			(at 1.905 -1.82499 270)
			(size 0.6096 2.3622)
			(layers "F.Cu" "F.Mask" "F.Paste")
			(net "Net_2031")
		)
		(pad "P2" smd rect
			(at 0.635 -1.82499 270)
			(size 0.6096 2.3622)
			(layers "F.Cu" "F.Mask" "F.Paste")
			(net "Net_2032")
		)
		(pad "P3" smd rect
			(at -0.635 -1.82499 270)
			(size 0.6096 2.3622)
			(layers "F.Cu" "F.Mask" "F.Paste")
			(net "Net_2033")
		)
		(pad "P4" smd rect
			(at -1.905 -1.82499 270)
			(size 0.6096 2.3622)
			(layers "F.Cu" "F.Mask" "F.Paste")
			(net "GND")
		)
		(pad "P5" smd rect
			(at -3.175 -1.82499 270)
			(size 0.6096 2.3622)
			(layers "F.Cu" "F.Mask" "F.Paste")
			(net "HDD_PRSNT_35")
		)
		(pad "P6" smd rect
			(at -4.445 -1.82499 270)
			(size 0.6096 2.3622)
			(layers "F.Cu" "F.Mask" "F.Paste")
			(net "GND")
		)
		(pad "P7" smd rect
			(at -5.715 -1.82499 270)
			(size 0.6096 2.3622)
			(layers "F.Cu" "F.Mask" "F.Paste")
			(net "5V_PRE_35")
		)
		(pad "P8" smd rect
			(at -6.985 -1.82499 270)
			(size 0.6096 2.3622)
			(layers "F.Cu" "F.Mask" "F.Paste")
			(net "P5V_HDD35")
		)
		(pad "P9" smd rect
			(at -8.255 -1.82499 270)
			(size 0.6096 2.3622)
			(layers "F.Cu" "F.Mask" "F.Paste")
			(net "P5V_HDD35")
		)
		(pad "P10" smd rect
			(at -9.525 -1.82499 270)
			(size 0.6096 2.3622)
			(layers "F.Cu" "F.Mask" "F.Paste")
			(net "GND")
		)
		(pad "P11" smd rect
			(at -10.795 -1.82499 270)
			(size 0.6096 2.3622)
			(layers "F.Cu" "F.Mask" "F.Paste")
			(net "ACT_HDD_35")
		)
		(pad "P12" smd rect
			(at -12.065 -1.82499 270)
			(size 0.6096 2.3622)
			(layers "F.Cu" "F.Mask" "F.Paste")
			(net "GND")
		)
		(pad "P13" smd rect
			(at -13.335 -1.82499 270)
			(size 0.6096 2.3622)
			(layers "F.Cu" "F.Mask" "F.Paste")
			(net "12V_PRE_35")
		)
		(pad "P14" smd rect
			(at -14.605 -1.82499 270)
			(size 0.6096 2.3622)
			(layers "F.Cu" "F.Mask" "F.Paste")
			(net "P12V_HDD35")
		)
		(pad "P15" smd rect
			(at -15.875 -1.82499 270)
			(size 0.6096 2.3622)
			(layers "F.Cu" "F.Mask" "F.Paste")
			(net "P12V_HDD35")
		)
		(pad "S1" smd rect
			(at 15.875 -1.82499 270)
			(size 0.6096 2.3622)
			(layers "F.Cu" "F.Mask" "F.Paste")
			(net "GND")
		)
		(pad "S2" smd rect
			(at 14.605 -1.82499 270)
			(size 0.6096 2.3622)
			(layers "F.Cu" "F.Mask" "F.Paste")
			(net "SAS_HDD_RX_P35")
		)
		(pad "S3" smd rect
			(at 13.335 -1.82499 270)
			(size 0.6096 2.3622)
			(layers "F.Cu" "F.Mask" "F.Paste")
			(net "SAS_HDD_RX_N35")
		)
		(pad "S4" smd rect
			(at 12.065 -1.82499 270)
			(size 0.6096 2.3622)
			(layers "F.Cu" "F.Mask" "F.Paste")
			(net "GND")
		)
		(pad "S5" smd rect
			(at 10.795 -1.82499 270)
			(size 0.6096 2.3622)
			(layers "F.Cu" "F.Mask" "F.Paste")
			(net "PHY_DRV_A_TO_SCC_A_35_DN")
		)
		(pad "S6" smd rect
			(at 9.525 -1.82499 270)
			(size 0.6096 2.3622)
			(layers "F.Cu" "F.Mask" "F.Paste")
			(net "PHY_DRV_A_TO_SCC_A_35_DP")
		)
		(pad "S7" smd rect
			(at 8.255 -1.82499 270)
			(size 0.6096 2.3622)
			(layers "F.Cu" "F.Mask" "F.Paste")
			(net "GND")
		)
		(pad "S8" smd rect
			(at 7.480046 2.845054 270)
			(size 0.508 2.3622)
			(layers "F.Cu" "F.Mask" "F.Paste")
			(net "GND")
		)
		(pad "S9" smd rect
			(at 6.679946 2.845054 270)
			(size 0.508 2.3622)
			(layers "F.Cu" "F.Mask" "F.Paste")
			(net "Net_474")
		)
		(pad "S10" smd rect
			(at 5.8801 2.845054 270)
			(size 0.508 2.3622)
			(layers "F.Cu" "F.Mask" "F.Paste")
			(net "Net_366")
		)
		(pad "S11" smd rect
			(at 5.08 2.845054 270)
			(size 0.508 2.3622)
			(layers "F.Cu" "F.Mask" "F.Paste")
			(net "GND")
		)
		(pad "S12" smd rect
			(at 4.2799 2.845054 270)
			(size 0.508 2.3622)
			(layers "F.Cu" "F.Mask" "F.Paste")
			(net "Net_402")
		)
		(pad "S13" smd rect
			(at 3.480054 2.845054 270)
			(size 0.508 2.3622)
			(layers "F.Cu" "F.Mask" "F.Paste")
			(net "Net_438")
		)
		(pad "S14" smd rect
			(at 2.679954 2.845054 270)
			(size 0.508 2.3622)
			(layers "F.Cu" "F.Mask" "F.Paste")
			(net "GND")
		)
		(zone
			(layer "F.Cu")
			(hatch none 0.5)
			(connect_pads
				(clearance 0)
			)
			(min_thickness 0.25)
			(keepout
				(tracks allowed)
				(vias not_allowed)
				(pads allowed)
				(copperpour not_allowed)
				(footprints allowed)
			)
			(placement
				(enabled no)
				(sheetname "")
			)
			(fill
				(thermal_gap 0.5)
				(thermal_bridge_width 0.5)
				(island_removal_mode 0)
			)
			(polygon
				(pts
					(xy 486.957624 -74.648568) (xy 479.883724 -74.648568) (xy 479.883724 -81.582768) (xy 480.988624 -81.582768)
					(xy 480.988624 -77.467968) (xy 485.611424 -77.467968) (xy 485.611424 -81.582768) (xy 486.957624 -81.582768)
				)
			)
		)
		(zone
			(layer "F.Cu")
			(hatch none 0.5)
			(connect_pads
				(clearance 0)
			)
			(min_thickness 0.25)
			(keepout
				(tracks not_allowed)
				(vias allowed)
				(pads allowed)
				(copperpour not_allowed)
				(footprints allowed)
			)
			(placement
				(enabled no)
				(sheetname "")
			)
			(fill
				(thermal_gap 0.5)
				(thermal_bridge_width 0.5)
				(island_removal_mode 0)
			)
			(polygon
				(pts
					(xy 486.957624 -74.648568) (xy 479.883724 -74.648568) (xy 479.883724 -81.582768) (xy 480.988624 -81.582768)
					(xy 480.988624 -77.467968) (xy 485.611424 -77.467968) (xy 485.611424 -81.582768) (xy 486.957624 -81.582768)
				)
			)
		)
		(zone
			(layer "F.Cu")
			(hatch none 0.5)
			(connect_pads
				(clearance 0)
			)
			(min_thickness 0.25)
			(keepout
				(tracks allowed)
				(vias not_allowed)
				(pads allowed)
				(copperpour not_allowed)
				(footprints allowed)
			)
			(placement
				(enabled no)
				(sheetname "")
			)
			(fill
				(thermal_gap 0.5)
				(thermal_bridge_width 0.5)
				(island_removal_mode 0)
			)
			(polygon
				(pts
					(xy 486.957624 -41.171368) (xy 479.883724 -41.171368) (xy 479.883724 -34.237168) (xy 480.988624 -34.237168)
					(xy 480.988624 -38.351968) (xy 485.611424 -38.351968) (xy 485.611424 -34.237168) (xy 486.957624 -34.237168)
				)
			)
		)
		(zone
			(layer "F.Cu")
			(hatch none 0.5)
			(connect_pads
				(clearance 0)
			)
			(min_thickness 0.25)
			(keepout
				(tracks not_allowed)
				(vias allowed)
				(pads allowed)
				(copperpour not_allowed)
				(footprints allowed)
			)
			(placement
				(enabled no)
				(sheetname "")
			)
			(fill
				(thermal_gap 0.5)
				(thermal_bridge_width 0.5)
				(island_removal_mode 0)
			)
			(polygon
				(pts
					(xy 486.957624 -41.171368) (xy 479.883724 -41.171368) (xy 479.883724 -34.237168) (xy 480.988624 -34.237168)
					(xy 480.988624 -38.351968) (xy 485.611424 -38.351968) (xy 485.611424 -34.237168) (xy 486.957624 -34.237168)
				)
			)
		)
		(zone
			(layers "F.Cu" "B.Cu" "In1.Cu" "In2.Cu" "In3.Cu" "In4.Cu" "In5.Cu" "In6.Cu"
				"In7.Cu" "In8.Cu" "In9.Cu" "In10.Cu"
			)
			(hatch none 0.5)
			(connect_pads
				(clearance 0)
			)
			(min_thickness 0.25)
			(keepout
				(tracks not_allowed)
				(vias allowed)
				(pads allowed)
				(copperpour not_allowed)
				(footprints allowed)
			)
			(placement
				(enabled no)
				(sheetname "")
			)
			(fill
				(thermal_gap 0.5)
				(thermal_bridge_width 0.5)
				(island_removal_mode 0)
			)
			(polygon
				(pts
					(arc
						(start 484.074724 -39.034974)
						(mid 482.525324 -39.034974)
						(end 484.074724 -39.034974)
					)
				)
			)
		)
		(zone
			(layers "F.Cu" "B.Cu" "In1.Cu" "In2.Cu" "In3.Cu" "In4.Cu" "In5.Cu" "In6.Cu"
				"In7.Cu" "In8.Cu" "In9.Cu" "In10.Cu"
			)
			(hatch none 0.5)
			(connect_pads
				(clearance 0)
			)
			(min_thickness 0.25)
			(keepout
				(tracks not_allowed)
				(vias allowed)
				(pads allowed)
				(copperpour not_allowed)
				(footprints allowed)
			)
			(placement
				(enabled no)
				(sheetname "")
			)
			(fill
				(thermal_gap 0.5)
				(thermal_bridge_width 0.5)
				(island_removal_mode 0)
			)
			(polygon
				(pts
					(arc
						(start 484.277924 -76.784962)
						(mid 482.322124 -76.784962)
						(end 484.277924 -76.784962)
					)
				)
			)
		)
	)
	(footprint ""
		(layer "F.Cu")
		(at 161.852102 -149.26437 180)
		(property "Reference" "R1068"
			(at 0 0 180)
			(layer "F.SilkS")
			(hide yes)
			(effects
				(font
					(size 1.27 1.27)
				)
			)
		)
		(property "Value" "1KR2F-3-GP"
			(at 0.064008 -3.993896 180)
			(unlocked yes)
			(layer "F.Fab")
			(hide yes)
			(effects
				(font
					(size 1.016 1.016)
					(thickness 0.1524)
				)
			)
		)
		(property "Device Type" "R402H16"
			(at 0.064008 -5.517896 180)
			(unlocked yes)
			(layer "F.Fab")
			(hide yes)
			(effects
				(font
					(size 1.016 1.016)
					(thickness 0.1524)
				)
			)
		)
		(duplicate_pad_numbers_are_jumpers no)
		(fp_line
			(start 0.508 -0.9398)
			(end -0.508 -0.9398)
			(stroke
				(width 0.1524)
				(type default)
			)
			(layer "F.SilkS")
		)
		(fp_line
			(start -0.508 -0.9398)
			(end -0.508 0.9398)
			(stroke
				(width 0.1524)
				(type default)
			)
			(layer "F.SilkS")
		)
		(fp_rect
			(start -0.508 0.9398)
			(end 0.508 -0.9398)
			(stroke
				(width 0)
				(type default)
			)
			(fill no)
			(layer "F.CrtYd")
		)
		(fp_rect
			(start -0.508 0.9398)
			(end 0.508 -0.9398)
			(stroke
				(width 0)
				(type default)
			)
			(fill no)
			(layer "F.Fab")
		)
		(pad "1" smd custom
			(at 0 -0.4445 180)
			(size 0.1397 0.1397)
			(layers "F.Cu" "F.Mask" "F.Paste")
			(net "MB0_CM_VOUT_R")
			(options
				(clearance outline)
				(anchor circle)
			)
			(primitives
				(gr_poly
					(pts
						(arc
							(start -0.1778 -0.2794)
							(mid -0.249642 -0.249642)
							(end -0.2794 -0.1778)
						)
						(arc
							(start -0.2794 0.1778)
							(mid -0.249642 0.249642)
							(end -0.1778 0.2794)
						)
						(arc
							(start 0.1778 0.2794)
							(mid 0.249642 0.249642)
							(end 0.2794 0.1778)
						)
						(arc
							(start 0.2794 -0.1778)
							(mid 0.249642 -0.249642)
							(end 0.1778 -0.2794)
						)
					)
					(width 0)
					(fill yes)
				)
			)
		)
		(pad "2" smd custom
			(at 0 0.4445 180)
			(size 0.1397 0.1397)
			(layers "F.Cu" "F.Mask" "F.Paste")
			(net "P12V_A_COMP")
			(options
				(clearance outline)
				(anchor circle)
			)
			(primitives
				(gr_poly
					(pts
						(arc
							(start -0.1778 -0.2794)
							(mid -0.249642 -0.249642)
							(end -0.2794 -0.1778)
						)
						(arc
							(start -0.2794 0.1778)
							(mid -0.249642 0.249642)
							(end -0.1778 0.2794)
						)
						(arc
							(start 0.1778 0.2794)
							(mid 0.249642 0.249642)
							(end 0.2794 0.1778)
						)
						(arc
							(start 0.2794 -0.1778)
							(mid 0.249642 -0.249642)
							(end 0.1778 -0.2794)
						)
					)
					(width 0)
					(fill yes)
				)
			)
		)
	)
	(footprint ""
		(layer "F.Cu")
		(at 464.2739 -279.443942 90)
		(property "Reference" "R376"
			(at 0 0 90)
			(layer "F.SilkS")
			(hide yes)
			(effects
				(font
					(size 1.27 1.27)
				)
			)
		)
		(property "Value" "200KR2F-L-GP"
			(at 0.064008 -3.993896 90)
			(unlocked yes)
			(layer "F.Fab")
			(hide yes)
			(effects
				(font
					(size 1.016 1.016)
					(thickness 0.1524)
				)
			)
		)
		(property "Device Type" "R402H16"
			(at 0.064008 -5.517896 90)
			(unlocked yes)
			(layer "F.Fab")
			(hide yes)
			(effects
				(font
					(size 1.016 1.016)
					(thickness 0.1524)
				)
			)
		)
		(duplicate_pad_numbers_are_jumpers no)
		(fp_line
			(start 0.508 -0.9398)
			(end -0.508 -0.9398)
			(stroke
				(width 0.1524)
				(type default)
			)
			(layer "F.SilkS")
		)
		(fp_line
			(start -0.508 -0.9398)
			(end -0.508 0.9398)
			(stroke
				(width 0.1524)
				(type default)
			)
			(layer "F.SilkS")
		)
		(fp_rect
			(start -0.508 0.9398)
			(end 0.508 -0.9398)
			(stroke
				(width 0)
				(type default)
			)
			(fill no)
			(layer "F.CrtYd")
		)
		(fp_rect
			(start -0.508 0.9398)
			(end 0.508 -0.9398)
			(stroke
				(width 0)
				(type default)
			)
			(fill no)
			(layer "F.Fab")
		)
		(pad "1" smd custom
			(at 0 -0.4445 90)
			(size 0.1397 0.1397)
			(layers "F.Cu" "F.Mask" "F.Paste")
			(net "SW_HDD_R10")
			(options
				(clearance outline)
				(anchor circle)
			)
			(primitives
				(gr_poly
					(pts
						(arc
							(start -0.1778 -0.2794)
							(mid -0.249642 -0.249642)
							(end -0.2794 -0.1778)
						)
						(arc
							(start -0.2794 0.1778)
							(mid -0.249642 0.249642)
							(end -0.1778 0.2794)
						)
						(arc
							(start 0.1778 0.2794)
							(mid 0.249642 0.249642)
							(end 0.2794 0.1778)
						)
						(arc
							(start 0.2794 -0.1778)
							(mid 0.249642 -0.249642)
							(end 0.1778 -0.2794)
						)
					)
					(width 0)
					(fill yes)
				)
			)
		)
		(pad "2" smd custom
			(at 0 0.4445 90)
			(size 0.1397 0.1397)
			(layers "F.Cu" "F.Mask" "F.Paste")
			(net "SW_HDD_N10")
			(options
				(clearance outline)
				(anchor circle)
			)
			(primitives
				(gr_poly
					(pts
						(arc
							(start -0.1778 -0.2794)
							(mid -0.249642 -0.249642)
							(end -0.2794 -0.1778)
						)
						(arc
							(start -0.2794 0.1778)
							(mid -0.249642 0.249642)
							(end -0.1778 0.2794)
						)
						(arc
							(start 0.1778 0.2794)
							(mid 0.249642 0.249642)
							(end 0.2794 0.1778)
						)
						(arc
							(start 0.2794 -0.1778)
							(mid 0.249642 -0.249642)
							(end 0.1778 -0.2794)
						)
					)
					(width 0)
					(fill yes)
				)
			)
		)
	)
	(footprint ""
		(layer "F.Cu")
		(at 266.991338 -152.04821)
		(property "Reference" "TP190"
			(at 0 0 0)
			(layer "F.SilkS")
			(hide yes)
			(effects
				(font
					(size 1.27 1.27)
				)
			)
		)
		(property "Value" "TPAD32-GP"
			(at -0.0508 -1.6764 0)
			(unlocked yes)
			(layer "F.Fab")
			(hide yes)
			(effects
				(font
					(size 1.016 1.016)
					(thickness 0.1524)
				)
			)
		)
		(property "Device Type" "TPAD32"
			(at -0.0508 -3.2004 0)
			(unlocked yes)
			(layer "F.Fab")
			(hide yes)
			(effects
				(font
					(size 1.016 1.016)
					(thickness 0.1524)
				)
			)
		)
		(duplicate_pad_numbers_are_jumpers no)
		(fp_poly
			(pts
				(arc
					(start 0.4064 0)
					(mid -0.4064 0)
					(end 0.4064 0)
				)
			)
			(stroke
				(width 0)
				(type default)
			)
			(fill no)
			(layer "F.CrtYd")
		)
		(fp_poly
			(pts
				(arc
					(start 0.7112 0)
					(mid -0.7112 0)
					(end 0.7112 0)
				)
			)
			(stroke
				(width 0)
				(type default)
			)
			(fill no)
			(layer "F.Fab")
		)
		(pad "1" smd circle
			(at 0 0)
			(size 0.8128 0.8128)
			(layers "F.Cu" "F.Mask" "F.Paste")
			(net "TP_COMP_B_KR_P0_TX_DN")
		)
	)
)
